# BASEBOARD_FAB2 (Tioga Pass) — schematic netlist excerpt (pin names and nets, part order shuffled) for the footprints in the layout excerpt that follows; sources: Cadence DE-HDL packaged netlist, KiCad conversion of Wiwynn_Tioga_Pass_MB.brd

C7B11  CAP  0.027UF 16V 10% X7R  pkg 0402  page 232 : A = VR_PVPP_DEF_SS ; B = AGND_PVPP_DEF
C1F16  CAP  0.22UF 16V 10% X7R  pkg 0402  page 181 : A = P3E_CPU1_PE3_MP_C_TXN<1> ; B = P3E_CPU1_PE3_MP_TXN<1>
R1F9  RES  0.0 5% EMPTY  pkg 0402  page 182 : A = FM_BMC_READY_N ; B = FAN_PWM_OUT_SYS0_R1

(kicad_pcb
	(version 20260206)
	(generator "pcbnew")
	(generator_version "10.0")
	(general
		(thickness 1.6)
		(legacy_teardrops no)
	)
	(paper "A4")
	(title_block
		(title "Wiwynn_Tioga_Pass_MB.brd")
		(comment 1 "Tioga Pass / footprints 673-675 of 4770")
	)
	(layers
		(0 "F.Cu" signal "TOP")
		(4 "In1.Cu" signal "L2GND")
		(6 "In2.Cu" signal "L3")
		(8 "In3.Cu" signal "L4GND")
		(10 "In4.Cu" signal "L5")
		(12 "In5.Cu" signal "L6GND")
		(14 "In6.Cu" signal "L7VCC")
		(16 "In7.Cu" signal "L8VCC")
		(18 "In8.Cu" signal "L9GND")
		(20 "In9.Cu" signal "L10")
		(22 "In10.Cu" signal "L11GND")
		(24 "In11.Cu" signal "L12")
		(26 "In12.Cu" signal "L13GND")
		(2 "B.Cu" signal "BOTTOM")
		(9 "F.Adhes" user "F.Adhesive")
		(11 "B.Adhes" user "B.Adhesive")
		(13 "F.Paste" user "Package Geometry/Pastemask Top")
		(15 "B.Paste" user "Package Geometry/Pastemask Bottom")
		(5 "F.SilkS" user "Ref Des/Silkscreen Top")
		(7 "B.SilkS" user "Ref Des/Silkscreen Bottom")
		(1 "F.Mask" user "Board Geometry/Soldermask Top")
		(3 "B.Mask" user "Board Geometry/Soldermask Bottom")
		(17 "Dwgs.User" user "User.Drawings")
		(19 "Cmts.User" user "User.Comments")
		(21 "Eco1.User" user "User.Eco1")
		(23 "Eco2.User" user "User.Eco2")
		(25 "Edge.Cuts" user "Board Geometry/Outline")
		(27 "Margin" user)
		(31 "F.CrtYd" user "Package Geometry/Place Bound Top")
		(29 "B.CrtYd" user "Package Geometry/Place Bound Bottom")
		(35 "F.Fab" user "Ref Des/Assembly Top")
		(33 "B.Fab" user "Ref Des/Assembly Bottom")
	)
	(footprint ""
		(layer "F.Cu")
		(at 14.1224 -37.719 -90)
		(property "Reference" "R1F9"
			(at 0 0 270)
			(layer "F.SilkS")
			(hide yes)
			(effects
				(font
					(size 1.27 1.27)
				)
			)
		)
		(property "Value" ""
			(at 0 0 270)
			(layer "F.Fab")
			(effects
				(font
					(size 1.27 1.27)
				)
			)
		)
		(duplicate_pad_numbers_are_jumpers no)
		(fp_poly
			(pts
				(xy -0.2794 -0.1016) (xy 0.2794 -0.1016) (xy 0.2794 0.9906) (xy -0.2794 0.9906)
			)
			(stroke
				(width 0)
				(type default)
			)
			(fill no)
			(layer "F.CrtYd")
		)
		(fp_line
			(start -0.2794 0.9906)
			(end 0.2794 0.9906)
			(stroke
				(width 0.1)
				(type default)
			)
			(layer "F.Fab")
		)
		(fp_line
			(start 0.2794 0.9906)
			(end 0.2794 -0.1016)
			(stroke
				(width 0.1)
				(type default)
			)
			(layer "F.Fab")
		)
		(fp_line
			(start -0.2794 -0.1016)
			(end -0.2794 0.9906)
			(stroke
				(width 0.1)
				(type default)
			)
			(layer "F.Fab")
		)
		(fp_line
			(start 0.2794 -0.1016)
			(end -0.2794 -0.1016)
			(stroke
				(width 0.1)
				(type default)
			)
			(layer "F.Fab")
		)
		(pad "1" smd rect
			(at 0 0 270)
			(size 0.508 0.508)
			(layers "F.Cu" "F.Mask" "F.Paste")
			(net "FM_BMC_READY_N")
		)
		(pad "2" smd rect
			(at 0 0.889 270)
			(size 0.508 0.508)
			(layers "F.Cu" "F.Mask" "F.Paste")
			(net "FAN_PWM_OUT_SYS0_R1")
		)
		(zone
			(layer "F.Cu")
			(hatch none 0.5)
			(connect_pads
				(clearance 0)
			)
			(min_thickness 0.25)
			(keepout
				(tracks not_allowed)
				(vias allowed)
				(pads allowed)
				(copperpour not_allowed)
				(footprints allowed)
			)
			(placement
				(enabled no)
				(sheetname "")
			)
			(fill
				(thermal_gap 0.5)
				(thermal_bridge_width 0.5)
				(island_removal_mode 0)
			)
			(polygon
				(pts
					(xy 13.4874 -37.973) (xy 13.4874 -37.465) (xy 13.8684 -37.465) (xy 13.8684 -37.973)
				)
			)
		)
		(zone
			(layer "F.Cu")
			(hatch none 0.5)
			(connect_pads
				(clearance 0)
			)
			(min_thickness 0.25)
			(keepout
				(tracks allowed)
				(vias not_allowed)
				(pads allowed)
				(copperpour not_allowed)
				(footprints allowed)
			)
			(placement
				(enabled no)
				(sheetname "")
			)
			(fill
				(thermal_gap 0.5)
				(thermal_bridge_width 0.5)
				(island_removal_mode 0)
			)
			(polygon
				(pts
					(xy 13.8684 -37.973) (xy 13.8684 -37.465) (xy 13.4874 -37.465) (xy 13.4874 -37.973)
				)
			)
		)
	)
	(footprint ""
		(layer "F.Cu")
		(at 13.8938 -25.908 90)
		(property "Reference" "C1F16"
			(at 0 0 90)
			(layer "F.SilkS")
			(hide yes)
			(effects
				(font
					(size 1.27 1.27)
				)
			)
		)
		(property "Value" ""
			(at 0 0 90)
			(layer "F.Fab")
			(effects
				(font
					(size 1.27 1.27)
				)
			)
		)
		(duplicate_pad_numbers_are_jumpers no)
		(fp_rect
			(start -0.3048 -0.1016)
			(end 0.3048 0.9906)
			(stroke
				(width 0)
				(type default)
			)
			(fill no)
			(layer "F.CrtYd")
		)
		(fp_line
			(start 0.3048 -0.1016)
			(end -0.3048 -0.1016)
			(stroke
				(width 0.1)
				(type default)
			)
			(layer "F.Fab")
		)
		(fp_line
			(start -0.3048 -0.1016)
			(end -0.3048 0.9906)
			(stroke
				(width 0.1)
				(type default)
			)
			(layer "F.Fab")
		)
		(fp_line
			(start 0.3048 0.9906)
			(end 0.3048 -0.1016)
			(stroke
				(width 0.1)
				(type default)
			)
			(layer "F.Fab")
		)
		(fp_line
			(start -0.3048 0.9906)
			(end 0.3048 0.9906)
			(stroke
				(width 0.1)
				(type default)
			)
			(layer "F.Fab")
		)
		(pad "1" smd rect
			(at 0 0 90)
			(size 0.508 0.508)
			(layers "F.Cu" "F.Mask" "F.Paste")
			(net "P3E_CPU1_PE3_MP_C_TXN<1>")
		)
		(pad "2" smd rect
			(at 0 0.889 90)
			(size 0.508 0.508)
			(layers "F.Cu" "F.Mask" "F.Paste")
			(net "P3E_CPU1_PE3_MP_TXN<1>")
		)
		(zone
			(layer "F.Cu")
			(hatch none 0.5)
			(connect_pads
				(clearance 0)
			)
			(min_thickness 0.25)
			(keepout
				(tracks not_allowed)
				(vias allowed)
				(pads allowed)
				(copperpour not_allowed)
				(footprints allowed)
			)
			(placement
				(enabled no)
				(sheetname "")
			)
			(fill
				(thermal_gap 0.5)
				(thermal_bridge_width 0.5)
				(island_removal_mode 0)
			)
			(polygon
				(pts
					(xy 14.1478 -25.654) (xy 14.5288 -25.654) (xy 14.5288 -26.162) (xy 14.1478 -26.162)
				)
			)
		)
		(zone
			(layer "F.Cu")
			(hatch none 0.5)
			(connect_pads
				(clearance 0)
			)
			(min_thickness 0.25)
			(keepout
				(tracks allowed)
				(vias not_allowed)
				(pads allowed)
				(copperpour not_allowed)
				(footprints allowed)
			)
			(placement
				(enabled no)
				(sheetname "")
			)
			(fill
				(thermal_gap 0.5)
				(thermal_bridge_width 0.5)
				(island_removal_mode 0)
			)
			(polygon
				(pts
					(xy 14.1478 -25.654) (xy 14.5288 -25.654) (xy 14.5288 -26.162) (xy 14.1478 -26.162)
				)
			)
		)
	)
	(footprint ""
		(layer "F.Cu")
		(at 339.9282 -128.3335)
		(property "Reference" "C7B11"
			(at 0 0 0)
			(layer "F.SilkS")
			(hide yes)
			(effects
				(font
					(size 1.27 1.27)
				)
			)
		)
		(property "Value" ""
			(at 0 0 0)
			(layer "F.Fab")
			(effects
				(font
					(size 1.27 1.27)
				)
			)
		)
		(duplicate_pad_numbers_are_jumpers no)
		(fp_poly
			(pts
				(xy 0.3048 -0.1016) (xy 0.3048 0.9906) (xy -0.3048 0.9906) (xy -0.3048 -0.1016)
			)
			(stroke
				(width 0)
				(type default)
			)
			(fill no)
			(layer "F.CrtYd")
		)
		(fp_line
			(start -0.3048 -0.1016)
			(end -0.3048 0.9906)
			(stroke
				(width 0.1)
				(type default)
			)
			(layer "F.Fab")
		)
		(fp_line
			(start -0.3048 0.9906)
			(end 0.3048 0.9906)
			(stroke
				(width 0.1)
				(type default)
			)
			(layer "F.Fab")
		)
		(fp_line
			(start 0.3048 -0.1016)
			(end -0.3048 -0.1016)
			(stroke
				(width 0.1)
				(type default)
			)
			(layer "F.Fab")
		)
		(fp_line
			(start 0.3048 0.9906)
			(end 0.3048 -0.1016)
			(stroke
				(width 0.1)
				(type default)
			)
			(layer "F.Fab")
		)
		(pad "1" smd rect
			(at 0 0)
			(size 0.508 0.508)
			(layers "F.Cu" "F.Mask" "F.Paste")
			(net "VR_PVPP_DEF_SS")
		)
		(pad "2" smd rect
			(at 0 0.889)
			(size 0.508 0.508)
			(layers "F.Cu" "F.Mask" "F.Paste")
			(net "AGND_PVPP_DEF")
		)
		(zone
			(layer "F.Cu")
			(hatch none 0.5)
			(connect_pads
				(clearance 0)
			)
			(min_thickness 0.25)
			(keepout
				(tracks allowed)
				(vias not_allowed)
				(pads allowed)
				(copperpour not_allowed)
				(footprints allowed)
			)
			(placement
				(enabled no)
				(sheetname "")
			)
			(fill
				(thermal_gap 0.5)
				(thermal_bridge_width 0.5)
				(island_removal_mode 0)
			)
			(polygon
				(pts
					(xy 339.6742 -128.0795) (xy 340.1822 -128.0795) (xy 340.1822 -127.6985) (xy 339.6742 -127.6985)
				)
			)
		)
		(zone
			(layer "F.Cu")
			(hatch none 0.5)
			(connect_pads
				(clearance 0)
			)
			(min_thickness 0.25)
			(keepout
				(tracks not_allowed)
				(vias allowed)
				(pads allowed)
				(copperpour not_allowed)
				(footprints allowed)
			)
			(placement
				(enabled no)
				(sheetname "")
			)
			(fill
				(thermal_gap 0.5)
				(thermal_bridge_width 0.5)
				(island_removal_mode 0)
			)
			(polygon
				(pts
					(xy 339.6742 -127.6985) (xy 340.1822 -127.6985) (xy 340.1822 -128.0795) (xy 339.6742 -128.0795)
				)
			)
		)
	)
)
